(kicad_pcb
	(version 20260206)
	(generator "pcbnew")
	(generator_version "10.0")
	(general
		(thickness 1.6)
		(legacy_teardrops no)
	)
	(paper "A4")
	(title_block
		(title "Bryce Canyon_SCC_16316-1_OCP.brd")
		(comment 1 "Bryce Canyon / footprints 1236-1242 of 1561")
	)
	(layers
		(0 "F.Cu" signal "TOP")
		(4 "In1.Cu" signal "L2GND")
		(6 "In2.Cu" signal "L3")
		(8 "In3.Cu" signal "L4VCC")
		(10 "In4.Cu" signal "L5VCC")
		(12 "In5.Cu" signal "L6")
		(14 "In6.Cu" signal "L7GND")
		(2 "B.Cu" signal "BOTTOM")
		(9 "F.Adhes" user "F.Adhesive")
		(11 "B.Adhes" user "B.Adhesive")
		(13 "F.Paste" user "Package Geometry/Pastemask Top")
		(15 "B.Paste" user "Package Geometry/Pastemask Bottom")
		(5 "F.SilkS" user "Ref Des/Silkscreen Top")
		(7 "B.SilkS" user "Ref Des/Silkscreen Bottom")
		(1 "F.Mask" user "Board Geometry/Soldermask Top")
		(3 "B.Mask" user "Board Geometry/Soldermask Bottom")
		(17 "Dwgs.User" user "User.Drawings")
		(19 "Cmts.User" user "User.Comments")
		(21 "Eco1.User" user "User.Eco1")
		(23 "Eco2.User" user "User.Eco2")
		(25 "Edge.Cuts" user "Board Geometry/Outline")
		(27 "Margin" user)
		(31 "F.CrtYd" user "Package Geometry/Place Bound Top")
		(29 "B.CrtYd" user "Package Geometry/Place Bound Bottom")
		(35 "F.Fab" user "Ref Des/Assembly Top")
		(33 "B.Fab" user "Ref Des/Assembly Bottom")
	)
	(footprint ""
		(layer "B.Cu")
		(at 110.363 -44.2214 180)
		(property "Reference" "C70"
			(at 0 0 0)
			(layer "B.SilkS")
			(hide yes)
			(effects
				(font
					(size 1.27 1.27)
				)
				(justify mirror)
			)
		)
		(property "Value" "SCD01U16V1KX-GP"
			(at 2.8321 -1.7399 180)
			(unlocked yes)
			(layer "B.Fab")
			(hide yes)
			(effects
				(font
					(size 1.016 1.016)
					(thickness 0.1524)
				)
				(justify mirror)
			)
		)
		(property "Device Type" "C0201H13"
			(at 2.8321 -3.2639 180)
			(unlocked yes)
			(layer "B.Fab")
			(hide yes)
			(effects
				(font
					(size 1.016 1.016)
					(thickness 0.1524)
				)
				(justify mirror)
			)
		)
		(duplicate_pad_numbers_are_jumpers no)
		(fp_rect
			(start 0.2794 0.6477)
			(end -0.2794 -0.6477)
			(stroke
				(width 0)
				(type default)
			)
			(fill no)
			(layer "B.CrtYd")
		)
		(fp_rect
			(start 0.2794 0.6477)
			(end -0.2794 -0.6477)
			(stroke
				(width 0)
				(type default)
			)
			(fill no)
			(layer "B.Fab")
		)
		(pad "1" smd custom
			(at 0 -0.2794)
			(size 0.0762 0.0762)
			(layers "B.Cu" "B.Mask" "B.Paste")
			(net "PHY_DPB_TO_SCC_25_DN")
			(options
				(clearance outline)
				(anchor circle)
			)
			(primitives
				(gr_poly
					(pts
						(arc
							(start 0.1524 0.127)
							(mid 0.137521 0.162921)
							(end 0.1016 0.1778)
						)
						(arc
							(start -0.1016 0.1778)
							(mid -0.137521 0.162921)
							(end -0.1524 0.127)
						)
						(arc
							(start -0.1524 -0.127)
							(mid -0.137521 -0.162921)
							(end -0.1016 -0.1778)
						)
						(arc
							(start 0.1016 -0.1778)
							(mid 0.137521 -0.162921)
							(end 0.1524 -0.127)
						)
					)
					(width 0)
					(fill yes)
				)
			)
		)
		(pad "2" smd custom
			(at 0 0.2794)
			(size 0.0762 0.0762)
			(layers "B.Cu" "B.Mask" "B.Paste")
			(net "PHY_DPB_TO_SCC_C_25_DN")
			(options
				(clearance outline)
				(anchor circle)
			)
			(primitives
				(gr_poly
					(pts
						(arc
							(start 0.1524 0.127)
							(mid 0.137521 0.162921)
							(end 0.1016 0.1778)
						)
						(arc
							(start -0.1016 0.1778)
							(mid -0.137521 0.162921)
							(end -0.1524 0.127)
						)
						(arc
							(start -0.1524 -0.127)
							(mid -0.137521 -0.162921)
							(end -0.1016 -0.1778)
						)
						(arc
							(start 0.1016 -0.1778)
							(mid 0.137521 -0.162921)
							(end 0.1524 -0.127)
						)
					)
					(width 0)
					(fill yes)
				)
			)
		)
	)
	(footprint ""
		(layer "B.Cu")
		(at 179.438808 -38.66769 90)
		(property "Reference" "C420"
			(at 0 0 90)
			(layer "B.SilkS")
			(hide yes)
			(effects
				(font
					(size 1.27 1.27)
				)
				(justify mirror)
			)
		)
		(property "Value" "SCD1U6D3V1KX-GP"
			(at 2.8321 -1.7399 90)
			(unlocked yes)
			(layer "B.Fab")
			(hide yes)
			(effects
				(font
					(size 1.016 1.016)
					(thickness 0.1524)
				)
				(justify mirror)
			)
		)
		(property "Device Type" "C0201H13"
			(at 2.8321 -3.2639 90)
			(unlocked yes)
			(layer "B.Fab")
			(hide yes)
			(effects
				(font
					(size 1.016 1.016)
					(thickness 0.1524)
				)
				(justify mirror)
			)
		)
		(duplicate_pad_numbers_are_jumpers no)
		(fp_rect
			(start 0.2794 0.6477)
			(end -0.2794 -0.6477)
			(stroke
				(width 0)
				(type default)
			)
			(fill no)
			(layer "B.CrtYd")
		)
		(fp_rect
			(start 0.2794 0.6477)
			(end -0.2794 -0.6477)
			(stroke
				(width 0)
				(type default)
			)
			(fill no)
			(layer "B.Fab")
		)
		(pad "1" smd custom
			(at 0 -0.2794 270)
			(size 0.0762 0.0762)
			(layers "B.Cu" "B.Mask" "B.Paste")
			(net "P0V975")
			(options
				(clearance outline)
				(anchor circle)
			)
			(primitives
				(gr_poly
					(pts
						(arc
							(start 0.1524 0.127)
							(mid 0.137521 0.162921)
							(end 0.1016 0.1778)
						)
						(arc
							(start -0.1016 0.1778)
							(mid -0.137521 0.162921)
							(end -0.1524 0.127)
						)
						(arc
							(start -0.1524 -0.127)
							(mid -0.137521 -0.162921)
							(end -0.1016 -0.1778)
						)
						(arc
							(start 0.1016 -0.1778)
							(mid 0.137521 -0.162921)
							(end 0.1524 -0.127)
						)
					)
					(width 0)
					(fill yes)
				)
			)
		)
		(pad "2" smd custom
			(at 0 0.2794 270)
			(size 0.0762 0.0762)
			(layers "B.Cu" "B.Mask" "B.Paste")
			(net "GND")
			(options
				(clearance outline)
				(anchor circle)
			)
			(primitives
				(gr_poly
					(pts
						(arc
							(start 0.1524 0.127)
							(mid 0.137521 0.162921)
							(end 0.1016 0.1778)
						)
						(arc
							(start -0.1016 0.1778)
							(mid -0.137521 0.162921)
							(end -0.1524 0.127)
						)
						(arc
							(start -0.1524 -0.127)
							(mid -0.137521 -0.162921)
							(end -0.1016 -0.1778)
						)
						(arc
							(start 0.1016 -0.1778)
							(mid 0.137521 -0.162921)
							(end 0.1524 -0.127)
						)
					)
					(width 0)
					(fill yes)
				)
			)
		)
	)
	(footprint ""
		(layer "B.Cu")
		(at 73.66 -51.689 180)
		(property "Reference" "C241"
			(at 0 0 0)
			(layer "B.SilkS")
			(hide yes)
			(effects
				(font
					(size 1.27 1.27)
				)
				(justify mirror)
			)
		)
		(property "Value" "SC100U6D3V6MX-GP"
			(at 0.0762 -5.1308 180)
			(unlocked yes)
			(layer "B.Fab")
			(hide yes)
			(effects
				(font
					(size 1.016 1.016)
					(thickness 0.1524)
				)
				(justify mirror)
			)
		)
		(property "Device Type" "C1206H71"
			(at 0.127 -6.6548 180)
			(unlocked yes)
			(layer "B.Fab")
			(hide yes)
			(effects
				(font
					(size 1.016 1.016)
					(thickness 0.1524)
				)
				(justify mirror)
			)
		)
		(duplicate_pad_numbers_are_jumpers no)
		(fp_line
			(start 1.016 2.2352)
			(end 1.016 0.8382)
			(stroke
				(width 0.1524)
				(type default)
			)
			(layer "B.SilkS")
		)
		(fp_line
			(start 1.016 -0.8382)
			(end 1.016 -2.2352)
			(stroke
				(width 0.1524)
				(type default)
			)
			(layer "B.SilkS")
		)
		(fp_line
			(start 1.016 -2.2352)
			(end -1.016 -2.2352)
			(stroke
				(width 0.1524)
				(type default)
			)
			(layer "B.SilkS")
		)
		(fp_line
			(start -1.016 2.2352)
			(end 1.016 2.2352)
			(stroke
				(width 0.1524)
				(type default)
			)
			(layer "B.SilkS")
		)
		(fp_line
			(start -1.016 0.8382)
			(end -1.016 2.2352)
			(stroke
				(width 0.1524)
				(type default)
			)
			(layer "B.SilkS")
		)
		(fp_line
			(start -1.016 -2.2352)
			(end -1.016 -0.8382)
			(stroke
				(width 0.1524)
				(type default)
			)
			(layer "B.SilkS")
		)
		(fp_rect
			(start 1.0922 2.3114)
			(end -1.0922 -2.3114)
			(stroke
				(width 0)
				(type default)
			)
			(fill no)
			(layer "B.CrtYd")
		)
		(fp_poly
			(pts
				(xy -1.0922 -2.3114) (xy -1.0922 2.3114) (xy 1.0922 2.3114) (xy 1.0922 -2.3114)
			)
			(stroke
				(width 0)
				(type default)
			)
			(fill no)
			(layer "B.Fab")
		)
		(pad "1" smd rect
			(at 0 -1.397)
			(size 1.651 1.27)
			(layers "B.Cu" "B.Mask" "B.Paste")
			(net "GB_VDDA")
		)
		(pad "2" smd rect
			(at 0 1.397)
			(size 1.651 1.27)
			(layers "B.Cu" "B.Mask" "B.Paste")
			(net "GND")
		)
	)
	(footprint ""
		(layer "B.Cu")
		(at 136.1948 -77.4954 -90)
		(property "Reference" "C5"
			(at 0 0 90)
			(layer "B.SilkS")
			(hide yes)
			(effects
				(font
					(size 1.27 1.27)
				)
				(justify mirror)
			)
		)
		(property "Value" "SCD01U16V1KX-GP"
			(at 2.8321 -1.7399 270)
			(unlocked yes)
			(layer "B.Fab")
			(hide yes)
			(effects
				(font
					(size 1.016 1.016)
					(thickness 0.1524)
				)
				(justify mirror)
			)
		)
		(property "Device Type" "C0201H13"
			(at 2.8321 -3.2639 270)
			(unlocked yes)
			(layer "B.Fab")
			(hide yes)
			(effects
				(font
					(size 1.016 1.016)
					(thickness 0.1524)
				)
				(justify mirror)
			)
		)
		(duplicate_pad_numbers_are_jumpers no)
		(fp_rect
			(start 0.2794 0.6477)
			(end -0.2794 -0.6477)
			(stroke
				(width 0)
				(type default)
			)
			(fill no)
			(layer "B.CrtYd")
		)
		(fp_rect
			(start 0.2794 0.6477)
			(end -0.2794 -0.6477)
			(stroke
				(width 0)
				(type default)
			)
			(fill no)
			(layer "B.Fab")
		)
		(pad "1" smd custom
			(at 0 -0.2794 90)
			(size 0.0762 0.0762)
			(layers "B.Cu" "B.Mask" "B.Paste")
			(net "PHY_CONN_TO_EXP_9_DP")
			(options
				(clearance outline)
				(anchor circle)
			)
			(primitives
				(gr_poly
					(pts
						(arc
							(start 0.1524 0.127)
							(mid 0.137521 0.162921)
							(end 0.1016 0.1778)
						)
						(arc
							(start -0.1016 0.1778)
							(mid -0.137521 0.162921)
							(end -0.1524 0.127)
						)
						(arc
							(start -0.1524 -0.127)
							(mid -0.137521 -0.162921)
							(end -0.1016 -0.1778)
						)
						(arc
							(start 0.1016 -0.1778)
							(mid 0.137521 -0.162921)
							(end 0.1524 -0.127)
						)
					)
					(width 0)
					(fill yes)
				)
			)
		)
		(pad "2" smd custom
			(at 0 0.2794 90)
			(size 0.0762 0.0762)
			(layers "B.Cu" "B.Mask" "B.Paste")
			(net "PHY_CONN_TO_EXP_C_9_DP")
			(options
				(clearance outline)
				(anchor circle)
			)
			(primitives
				(gr_poly
					(pts
						(arc
							(start 0.1524 0.127)
							(mid 0.137521 0.162921)
							(end 0.1016 0.1778)
						)
						(arc
							(start -0.1016 0.1778)
							(mid -0.137521 0.162921)
							(end -0.1524 0.127)
						)
						(arc
							(start -0.1524 -0.127)
							(mid -0.137521 -0.162921)
							(end -0.1016 -0.1778)
						)
						(arc
							(start 0.1016 -0.1778)
							(mid 0.137521 -0.162921)
							(end 0.1524 -0.127)
						)
					)
					(width 0)
					(fill yes)
				)
			)
		)
	)
	(footprint ""
		(layer "B.Cu")
		(at 203.073 -24.638)
		(property "Reference" "Q4"
			(at 0 0 0)
			(layer "B.SilkS")
			(hide yes)
			(effects
				(font
					(size 1.27 1.27)
				)
				(justify mirror)
			)
		)
		(property "Value" "SSM3K324R-GP"
			(at -0.127 -8.9662 0)
			(unlocked yes)
			(layer "B.Fab")
			(hide yes)
			(effects
				(font
					(size 1.016 1.016)
					(thickness 0.1524)
				)
				(justify mirror)
			)
		)
		(property "Device Type" "SOT23DGS2D4H35"
			(at -0.127 -10.4902 0)
			(unlocked yes)
			(layer "B.Fab")
			(hide yes)
			(effects
				(font
					(size 1.016 1.016)
					(thickness 0.1524)
				)
				(justify mirror)
			)
		)
		(duplicate_pad_numbers_are_jumpers no)
		(fp_line
			(start -1.651 -1.778)
			(end 1.651 -1.778)
			(stroke
				(width 0.1524)
				(type default)
			)
			(layer "B.SilkS")
		)
		(fp_line
			(start -1.651 1.778)
			(end -1.651 -1.778)
			(stroke
				(width 0.1524)
				(type default)
			)
			(layer "B.SilkS")
		)
		(fp_line
			(start 1.651 -1.778)
			(end 1.651 1.778)
			(stroke
				(width 0.1524)
				(type default)
			)
			(layer "B.SilkS")
		)
		(fp_line
			(start 1.651 1.778)
			(end -1.651 1.778)
			(stroke
				(width 0.1524)
				(type default)
			)
			(layer "B.SilkS")
		)
		(fp_poly
			(pts
				(xy 1.778 1.8796) (xy 1.778 -1.8796) (xy -1.778 -1.8796) (xy -1.778 1.8796)
			)
			(stroke
				(width 0)
				(type default)
			)
			(fill no)
			(layer "B.CrtYd")
		)
		(fp_poly
			(pts
				(xy 1.778 1.8796) (xy 1.778 -1.8796) (xy -1.778 -1.8796) (xy -1.778 1.8796)
			)
			(stroke
				(width 0)
				(type default)
			)
			(fill no)
			(layer "B.Fab")
		)
		(pad "D" smd custom
			(at 0 -0.9525 180)
			(size 0.1905 0.1905)
			(layers "B.Cu" "B.Mask" "B.Paste")
			(net "SYS_ERROR_LED_D")
			(options
				(clearance outline)
				(anchor circle)
			)
			(primitives
				(gr_poly
					(pts
						(arc
							(start -0.1778 -0.5715)
							(mid -0.321484 -0.511984)
							(end -0.381 -0.3683)
						)
						(arc
							(start -0.381 0.3683)
							(mid -0.321484 0.511984)
							(end -0.1778 0.5715)
						)
						(arc
							(start 0.1778 0.5715)
							(mid 0.321484 0.511984)
							(end 0.381 0.3683)
						)
						(arc
							(start 0.381 -0.3683)
							(mid 0.321484 -0.511984)
							(end 0.1778 -0.5715)
						)
					)
					(width 0)
					(fill yes)
				)
			)
		)
		(pad "G" smd custom
			(at 0.98425 0.9525 180)
			(size 0.1905 0.1905)
			(layers "B.Cu" "B.Mask" "B.Paste")
			(net "SYS_ERR_0")
			(options
				(clearance outline)
				(anchor circle)
			)
			(primitives
				(gr_poly
					(pts
						(arc
							(start -0.1778 -0.5715)
							(mid -0.321484 -0.511984)
							(end -0.381 -0.3683)
						)
						(arc
							(start -0.381 0.3683)
							(mid -0.321484 0.511984)
							(end -0.1778 0.5715)
						)
						(arc
							(start 0.1778 0.5715)
							(mid 0.321484 0.511984)
							(end 0.381 0.3683)
						)
						(arc
							(start 0.381 -0.3683)
							(mid 0.321484 -0.511984)
							(end 0.1778 -0.5715)
						)
					)
					(width 0)
					(fill yes)
				)
			)
		)
		(pad "S" smd custom
			(at -0.98425 0.9525 180)
			(size 0.1905 0.1905)
			(layers "B.Cu" "B.Mask" "B.Paste")
			(net "GND")
			(options
				(clearance outline)
				(anchor circle)
			)
			(primitives
				(gr_poly
					(pts
						(arc
							(start -0.1778 -0.5715)
							(mid -0.321484 -0.511984)
							(end -0.381 -0.3683)
						)
						(arc
							(start -0.381 0.3683)
							(mid -0.321484 0.511984)
							(end -0.1778 0.5715)
						)
						(arc
							(start 0.1778 0.5715)
							(mid 0.321484 0.511984)
							(end 0.381 0.3683)
						)
						(arc
							(start 0.381 -0.3683)
							(mid 0.321484 -0.511984)
							(end 0.1778 -0.5715)
						)
					)
					(width 0)
					(fill yes)
				)
			)
		)
	)
	(footprint ""
		(layer "B.Cu")
		(at 118.27256 -74.618088 180)
		(property "Reference" "C122"
			(at 0 0 0)
			(layer "B.SilkS")
			(hide yes)
			(effects
				(font
					(size 1.27 1.27)
				)
				(justify mirror)
			)
		)
		(property "Value" "SC10U6D3V2MX-GP-U"
			(at 1.524 -1.905 180)
			(unlocked yes)
			(layer "B.Fab")
			(hide yes)
			(effects
				(font
					(size 1.016 1.016)
					(thickness 0.1524)
				)
				(justify mirror)
			)
		)
		(property "Device Type" "C402-TO0D2H28"
			(at 1.524 -3.429 180)
			(unlocked yes)
			(layer "B.Fab")
			(hide yes)
			(effects
				(font
					(size 1.016 1.016)
					(thickness 0.1524)
				)
				(justify mirror)
			)
		)
		(duplicate_pad_numbers_are_jumpers no)
		(fp_rect
			(start 0.4826 0.889)
			(end -0.4826 -0.889)
			(stroke
				(width 0)
				(type default)
			)
			(fill no)
			(layer "B.CrtYd")
		)
		(fp_rect
			(start 0.4826 0.889)
			(end -0.4826 -0.889)
			(stroke
				(width 0)
				(type default)
			)
			(fill no)
			(layer "B.Fab")
		)
		(pad "1" smd custom
			(at 0 -0.4572)
			(size 0.1524 0.1524)
			(layers "B.Cu" "B.Mask" "B.Paste")
			(net "P1V8_E")
			(options
				(clearance outline)
				(anchor circle)
			)
			(primitives
				(gr_poly
					(pts
						(arc
							(start -0.254 -0.3048)
							(mid -0.325842 -0.275042)
							(end -0.3556 -0.2032)
						)
						(arc
							(start -0.3556 0.2032)
							(mid -0.325842 0.275042)
							(end -0.254 0.3048)
						)
						(arc
							(start 0.254 0.3048)
							(mid 0.325842 0.275042)
							(end 0.3556 0.2032)
						)
						(arc
							(start 0.3556 -0.2032)
							(mid 0.325842 -0.275042)
							(end 0.254 -0.3048)
						)
					)
					(width 0)
					(fill yes)
				)
			)
		)
		(pad "2" smd custom
			(at 0 0.4572)
			(size 0.1524 0.1524)
			(layers "B.Cu" "B.Mask" "B.Paste")
			(net "GND")
			(options
				(clearance outline)
				(anchor circle)
			)
			(primitives
				(gr_poly
					(pts
						(arc
							(start -0.254 -0.3048)
							(mid -0.325842 -0.275042)
							(end -0.3556 -0.2032)
						)
						(arc
							(start -0.3556 0.2032)
							(mid -0.325842 0.275042)
							(end -0.254 0.3048)
						)
						(arc
							(start 0.254 0.3048)
							(mid 0.325842 0.275042)
							(end 0.3556 0.2032)
						)
						(arc
							(start 0.3556 -0.2032)
							(mid 0.325842 -0.275042)
							(end 0.254 -0.3048)
						)
					)
					(width 0)
					(fill yes)
				)
			)
		)
	)
	(footprint ""
		(layer "B.Cu")
		(at 166.88943 -46.754542)
		(property "Reference" "C452"
			(at 0 0 0)
			(layer "B.SilkS")
			(hide yes)
			(effects
				(font
					(size 1.27 1.27)
				)
				(justify mirror)
			)
		)
		(property "Value" "SCD1U6D3V1KX-GP"
			(at 2.8321 -1.7399 0)
			(unlocked yes)
			(layer "B.Fab")
			(hide yes)
			(effects
				(font
					(size 1.016 1.016)
					(thickness 0.1524)
				)
				(justify mirror)
			)
		)
		(property "Device Type" "C0201H13"
			(at 2.8321 -3.2639 0)
			(unlocked yes)
			(layer "B.Fab")
			(hide yes)
			(effects
				(font
					(size 1.016 1.016)
					(thickness 0.1524)
				)
				(justify mirror)
			)
		)
		(duplicate_pad_numbers_are_jumpers no)
		(fp_rect
			(start 0.2794 0.6477)
			(end -0.2794 -0.6477)
			(stroke
				(width 0)
				(type default)
			)
			(fill no)
			(layer "B.CrtYd")
		)
		(fp_rect
			(start 0.2794 0.6477)
			(end -0.2794 -0.6477)
			(stroke
				(width 0)
				(type default)
			)
			(fill no)
			(layer "B.Fab")
		)
		(pad "1" smd custom
			(at 0 -0.2794 180)
			(size 0.0762 0.0762)
			(layers "B.Cu" "B.Mask" "B.Paste")
			(net "P1V8_C")
			(options
				(clearance outline)
				(anchor circle)
			)
			(primitives
				(gr_poly
					(pts
						(arc
							(start 0.1524 0.127)
							(mid 0.137521 0.162921)
							(end 0.1016 0.1778)
						)
						(arc
							(start -0.1016 0.1778)
							(mid -0.137521 0.162921)
							(end -0.1524 0.127)
						)
						(arc
							(start -0.1524 -0.127)
							(mid -0.137521 -0.162921)
							(end -0.1016 -0.1778)
						)
						(arc
							(start 0.1016 -0.1778)
							(mid 0.137521 -0.162921)
							(end 0.1524 -0.127)
						)
					)
					(width 0)
					(fill yes)
				)
			)
		)
		(pad "2" smd custom
			(at 0 0.2794 180)
			(size 0.0762 0.0762)
			(layers "B.Cu" "B.Mask" "B.Paste")
			(net "GND")
			(options
				(clearance outline)
				(anchor circle)
			)
			(primitives
				(gr_poly
					(pts
						(arc
							(start 0.1524 0.127)
							(mid 0.137521 0.162921)
							(end 0.1016 0.1778)
						)
						(arc
							(start -0.1016 0.1778)
							(mid -0.137521 0.162921)
							(end -0.1524 0.127)
						)
						(arc
							(start -0.1524 -0.127)
							(mid -0.137521 -0.162921)
							(end -0.1016 -0.1778)
						)
						(arc
							(start 0.1016 -0.1778)
							(mid 0.137521 -0.162921)
							(end 0.1524 -0.127)
						)
					)
					(width 0)
					(fill yes)
				)
			)
		)
	)
)
